(kicad_pcb
	(version 20260206)
	(generator "pcbnew")
	(generator_version "10.0")
	(general
		(thickness 1.6)
		(legacy_teardrops no)
	)
	(paper "A4")
	(title_block
		(title "01162023_DA0F0TEBIF0_F0T_Expander_BD_F_brd_V02_OCP.brd")
		(comment 1 "Grand Teton / footprints 1569-1576 of 9728")
	)
	(layers
		(0 "F.Cu" signal "TOP")
		(4 "In1.Cu" signal "GND")
		(6 "In2.Cu" signal "VCC")
		(8 "In3.Cu" signal "VCC1")
		(10 "In4.Cu" signal "GND1")
		(12 "In5.Cu" signal "IN1")
		(14 "In6.Cu" signal "GND2")
		(16 "In7.Cu" signal "IN2")
		(18 "In8.Cu" signal "GND3")
		(20 "In9.Cu" signal "IN3")
		(22 "In10.Cu" signal "GND4")
		(24 "In11.Cu" signal "IN4")
		(26 "In12.Cu" signal "GND5")
		(28 "In13.Cu" signal "IN5")
		(30 "In14.Cu" signal "GND6")
		(32 "In15.Cu" signal "IN6")
		(34 "In16.Cu" signal "GND7")
		(2 "B.Cu" signal "BOTTOM")
		(9 "F.Adhes" user "F.Adhesive")
		(11 "B.Adhes" user "B.Adhesive")
		(13 "F.Paste" user "Package Geometry/Pastemask Top")
		(15 "B.Paste" user "Package Geometry/Pastemask Bottom")
		(5 "F.SilkS" user "Ref Des/Silkscreen Top")
		(7 "B.SilkS" user "Ref Des/Silkscreen Bottom")
		(1 "F.Mask" user "Board Geometry/Soldermask Top")
		(3 "B.Mask" user "Board Geometry/Soldermask Bottom")
		(17 "Dwgs.User" user "User.Drawings")
		(19 "Cmts.User" user "User.Comments")
		(21 "Eco1.User" user "User.Eco1")
		(23 "Eco2.User" user "User.Eco2")
		(25 "Edge.Cuts" user "Board Geometry/Outline")
		(27 "Margin" user)
		(31 "F.CrtYd" user "Package Geometry/Place Bound Top")
		(29 "B.CrtYd" user "Package Geometry/Place Bound Bottom")
		(35 "F.Fab" user "Ref Des/Assembly Top")
		(33 "B.Fab" user "Ref Des/Assembly Bottom")
	)
	(footprint ""
		(layer "F.Cu")
		(at 380.770384 -252.356874 -90)
		(property "Reference" "R1433"
			(at 0 0 270)
			(layer "F.SilkS")
			(hide yes)
			(effects
				(font
					(size 1.27 1.27)
				)
			)
		)
		(property "Value" ""
			(at 0 0 270)
			(layer "F.Fab")
			(effects
				(font
					(size 1.27 1.27)
				)
			)
		)
		(duplicate_pad_numbers_are_jumpers no)
		(fp_line
			(start -0.7874 0.4064)
			(end -0.7874 -0.4064)
			(stroke
				(width 0.1524)
				(type default)
			)
			(layer "F.SilkS")
		)
		(fp_line
			(start 0.7874 0.4064)
			(end -0.7874 0.4064)
			(stroke
				(width 0.1524)
				(type default)
			)
			(layer "F.SilkS")
		)
		(fp_line
			(start -0.7874 -0.4064)
			(end 0.7874 -0.4064)
			(stroke
				(width 0.1524)
				(type default)
			)
			(layer "F.SilkS")
		)
		(fp_line
			(start 0.7874 -0.4064)
			(end 0.7874 0.4064)
			(stroke
				(width 0.1524)
				(type default)
			)
			(layer "F.SilkS")
		)
		(fp_line
			(start -0.67945 0.3048)
			(end -0.67945 -0.305054)
			(stroke
				(width 0.1)
				(type default)
			)
			(layer "F.Fab")
		)
		(fp_line
			(start -0.12065 0.3048)
			(end -0.67945 0.3048)
			(stroke
				(width 0.1)
				(type default)
			)
			(layer "F.Fab")
		)
		(fp_line
			(start 0.120396 0.3048)
			(end 0.120396 0.2794)
			(stroke
				(width 0.1)
				(type default)
			)
			(layer "F.Fab")
		)
		(fp_line
			(start 0.67945 0.3048)
			(end 0.120396 0.3048)
			(stroke
				(width 0.1)
				(type default)
			)
			(layer "F.Fab")
		)
		(fp_line
			(start -0.12065 0.2794)
			(end -0.12065 0.3048)
			(stroke
				(width 0.1)
				(type default)
			)
			(layer "F.Fab")
		)
		(fp_line
			(start 0.120396 0.2794)
			(end -0.12065 0.2794)
			(stroke
				(width 0.1)
				(type default)
			)
			(layer "F.Fab")
		)
		(fp_line
			(start -0.12065 -0.2794)
			(end 0.12065 -0.2794)
			(stroke
				(width 0.1)
				(type default)
			)
			(layer "F.Fab")
		)
		(fp_line
			(start 0.12065 -0.2794)
			(end 0.12065 -0.3048)
			(stroke
				(width 0.1)
				(type default)
			)
			(layer "F.Fab")
		)
		(fp_line
			(start 0.12065 -0.3048)
			(end 0.67945 -0.3048)
			(stroke
				(width 0.1)
				(type default)
			)
			(layer "F.Fab")
		)
		(fp_line
			(start 0.67945 -0.3048)
			(end 0.67945 0.3048)
			(stroke
				(width 0.1)
				(type default)
			)
			(layer "F.Fab")
		)
		(fp_line
			(start -0.67945 -0.305054)
			(end -0.12065 -0.305054)
			(stroke
				(width 0.1)
				(type default)
			)
			(layer "F.Fab")
		)
		(fp_line
			(start -0.12065 -0.305054)
			(end -0.12065 -0.2794)
			(stroke
				(width 0.1)
				(type default)
			)
			(layer "F.Fab")
		)
		(pad "1" smd circle
			(at -0.40005 0 270)
			(size 0 0)
			(layers "F.Cu" "F.Mask" "F.Paste")
			(net "GND")
		)
		(pad "2" smd circle
			(at 0.40005 0 270)
			(size 0 0)
			(layers "F.Cu" "F.Mask" "F.Paste")
			(net "PEX3_MODE_SEL8")
		)
	)
	(footprint ""
		(layer "F.Cu")
		(at 447.449956 -308.61)
		(property "Reference" "H134"
			(at -2.435098 -4.410964 0)
			(unlocked yes)
			(layer "F.SilkS")
			(effects
				(font
					(size 0.7874 0.5842)
					(thickness 0.1524)
				)
				(justify left)
			)
		)
		(property "Value" ""
			(at 0 0 0)
			(layer "F.Fab")
			(effects
				(font
					(size 1.27 1.27)
				)
			)
		)
		(duplicate_pad_numbers_are_jumpers no)
		(pad "1" thru_hole circle
			(at 0 0)
			(size 6.5024 6.5024)
			(drill 3.2004)
			(layers "*.Cu" "*.Mask")
			(remove_unused_layers no)
			(net "GND")
			(clearance -1.397)
		)
	)
	(footprint ""
		(layer "F.Cu")
		(at 106.596942 -116.611654 180)
		(property "Reference" "PR6868"
			(at 0 0 180)
			(layer "F.SilkS")
			(hide yes)
			(effects
				(font
					(size 1.27 1.27)
				)
			)
		)
		(property "Value" ""
			(at 0 0 180)
			(layer "F.Fab")
			(effects
				(font
					(size 1.27 1.27)
				)
			)
		)
		(duplicate_pad_numbers_are_jumpers no)
		(fp_line
			(start 0.7874 0.4064)
			(end -0.7874 0.4064)
			(stroke
				(width 0.1524)
				(type default)
			)
			(layer "F.SilkS")
		)
		(fp_line
			(start 0.7874 -0.4064)
			(end 0.7874 0.4064)
			(stroke
				(width 0.1524)
				(type default)
			)
			(layer "F.SilkS")
		)
		(fp_line
			(start -0.7874 0.4064)
			(end -0.7874 -0.4064)
			(stroke
				(width 0.1524)
				(type default)
			)
			(layer "F.SilkS")
		)
		(fp_line
			(start -0.7874 -0.4064)
			(end 0.7874 -0.4064)
			(stroke
				(width 0.1524)
				(type default)
			)
			(layer "F.SilkS")
		)
		(fp_line
			(start 0.67945 0.3048)
			(end 0.120396 0.3048)
			(stroke
				(width 0.1)
				(type default)
			)
			(layer "F.Fab")
		)
		(fp_line
			(start 0.67945 -0.3048)
			(end 0.67945 0.3048)
			(stroke
				(width 0.1)
				(type default)
			)
			(layer "F.Fab")
		)
		(fp_line
			(start 0.12065 -0.2794)
			(end 0.12065 -0.3048)
			(stroke
				(width 0.1)
				(type default)
			)
			(layer "F.Fab")
		)
		(fp_line
			(start 0.12065 -0.3048)
			(end 0.67945 -0.3048)
			(stroke
				(width 0.1)
				(type default)
			)
			(layer "F.Fab")
		)
		(fp_line
			(start 0.120396 0.3048)
			(end 0.120396 0.2794)
			(stroke
				(width 0.1)
				(type default)
			)
			(layer "F.Fab")
		)
		(fp_line
			(start 0.120396 0.2794)
			(end -0.12065 0.2794)
			(stroke
				(width 0.1)
				(type default)
			)
			(layer "F.Fab")
		)
		(fp_line
			(start -0.12065 0.3048)
			(end -0.67945 0.3048)
			(stroke
				(width 0.1)
				(type default)
			)
			(layer "F.Fab")
		)
		(fp_line
			(start -0.12065 0.2794)
			(end -0.12065 0.3048)
			(stroke
				(width 0.1)
				(type default)
			)
			(layer "F.Fab")
		)
		(fp_line
			(start -0.12065 -0.2794)
			(end 0.12065 -0.2794)
			(stroke
				(width 0.1)
				(type default)
			)
			(layer "F.Fab")
		)
		(fp_line
			(start -0.12065 -0.305054)
			(end -0.12065 -0.2794)
			(stroke
				(width 0.1)
				(type default)
			)
			(layer "F.Fab")
		)
		(fp_line
			(start -0.67945 0.3048)
			(end -0.67945 -0.305054)
			(stroke
				(width 0.1)
				(type default)
			)
			(layer "F.Fab")
		)
		(fp_line
			(start -0.67945 -0.305054)
			(end -0.12065 -0.305054)
			(stroke
				(width 0.1)
				(type default)
			)
			(layer "F.Fab")
		)
		(pad "1" smd circle
			(at -0.40005 0 180)
			(size 0 0)
			(layers "F.Cu" "F.Mask" "F.Paste")
			(net "P12V_NIC1_CO_OV_FB")
		)
		(pad "2" smd circle
			(at 0.40005 0 180)
			(size 0 0)
			(layers "F.Cu" "F.Mask" "F.Paste")
			(net "P12V_AUX")
		)
	)
	(footprint ""
		(layer "F.Cu")
		(at 327.992232 -29.139642 180)
		(property "Reference" "C517"
			(at 0 0 180)
			(layer "F.SilkS")
			(hide yes)
			(effects
				(font
					(size 1.27 1.27)
				)
			)
		)
		(property "Value" ""
			(at 0 0 180)
			(layer "F.Fab")
			(effects
				(font
					(size 1.27 1.27)
				)
			)
		)
		(duplicate_pad_numbers_are_jumpers no)
		(fp_line
			(start 0.299974 0.150114)
			(end -0.299974 0.150114)
			(stroke
				(width 0.1)
				(type default)
			)
			(layer "F.Fab")
		)
		(fp_line
			(start 0.299974 -0.150114)
			(end 0.299974 0.150114)
			(stroke
				(width 0.1)
				(type default)
			)
			(layer "F.Fab")
		)
		(fp_line
			(start -0.299974 0.150114)
			(end -0.299974 -0.150114)
			(stroke
				(width 0.1)
				(type default)
			)
			(layer "F.Fab")
		)
		(fp_line
			(start -0.299974 -0.150114)
			(end 0.299974 -0.150114)
			(stroke
				(width 0.1)
				(type default)
			)
			(layer "F.Fab")
		)
		(pad "1" smd rect
			(at -0.2667 0 180)
			(size 0.3048 0.381)
			(layers "F.Cu" "F.Mask" "F.Paste")
			(net "P5E_PEX2_STN2_TX_DP<32>")
		)
		(pad "2" smd rect
			(at 0.2667 0 180)
			(size 0.3048 0.381)
			(layers "F.Cu" "F.Mask" "F.Paste")
			(net "P5E_PEX2_STN2_TX_C_DP<32>")
		)
	)
	(footprint ""
		(layer "F.Cu")
		(at 196.956172 -32.848042 -90)
		(property "Reference" "R6067"
			(at 0 0 270)
			(layer "F.SilkS")
			(hide yes)
			(effects
				(font
					(size 1.27 1.27)
				)
			)
		)
		(property "Value" ""
			(at 0 0 270)
			(layer "F.Fab")
			(effects
				(font
					(size 1.27 1.27)
				)
			)
		)
		(duplicate_pad_numbers_are_jumpers no)
		(fp_line
			(start -0.7874 0.4064)
			(end -0.7874 -0.4064)
			(stroke
				(width 0.1524)
				(type default)
			)
			(layer "F.SilkS")
		)
		(fp_line
			(start 0.7874 0.4064)
			(end -0.7874 0.4064)
			(stroke
				(width 0.1524)
				(type default)
			)
			(layer "F.SilkS")
		)
		(fp_line
			(start -0.7874 -0.4064)
			(end 0.7874 -0.4064)
			(stroke
				(width 0.1524)
				(type default)
			)
			(layer "F.SilkS")
		)
		(fp_line
			(start 0.7874 -0.4064)
			(end 0.7874 0.4064)
			(stroke
				(width 0.1524)
				(type default)
			)
			(layer "F.SilkS")
		)
		(fp_line
			(start -0.67945 0.3048)
			(end -0.67945 -0.305054)
			(stroke
				(width 0.1)
				(type default)
			)
			(layer "F.Fab")
		)
		(fp_line
			(start -0.12065 0.3048)
			(end -0.67945 0.3048)
			(stroke
				(width 0.1)
				(type default)
			)
			(layer "F.Fab")
		)
		(fp_line
			(start 0.120396 0.3048)
			(end 0.120396 0.2794)
			(stroke
				(width 0.1)
				(type default)
			)
			(layer "F.Fab")
		)
		(fp_line
			(start 0.67945 0.3048)
			(end 0.120396 0.3048)
			(stroke
				(width 0.1)
				(type default)
			)
			(layer "F.Fab")
		)
		(fp_line
			(start -0.12065 0.2794)
			(end -0.12065 0.3048)
			(stroke
				(width 0.1)
				(type default)
			)
			(layer "F.Fab")
		)
		(fp_line
			(start 0.120396 0.2794)
			(end -0.12065 0.2794)
			(stroke
				(width 0.1)
				(type default)
			)
			(layer "F.Fab")
		)
		(fp_line
			(start -0.12065 -0.2794)
			(end 0.12065 -0.2794)
			(stroke
				(width 0.1)
				(type default)
			)
			(layer "F.Fab")
		)
		(fp_line
			(start 0.12065 -0.2794)
			(end 0.12065 -0.3048)
			(stroke
				(width 0.1)
				(type default)
			)
			(layer "F.Fab")
		)
		(fp_line
			(start 0.12065 -0.3048)
			(end 0.67945 -0.3048)
			(stroke
				(width 0.1)
				(type default)
			)
			(layer "F.Fab")
		)
		(fp_line
			(start 0.67945 -0.3048)
			(end 0.67945 0.3048)
			(stroke
				(width 0.1)
				(type default)
			)
			(layer "F.Fab")
		)
		(fp_line
			(start -0.67945 -0.305054)
			(end -0.12065 -0.305054)
			(stroke
				(width 0.1)
				(type default)
			)
			(layer "F.Fab")
		)
		(fp_line
			(start -0.12065 -0.305054)
			(end -0.12065 -0.2794)
			(stroke
				(width 0.1)
				(type default)
			)
			(layer "F.Fab")
		)
		(pad "1" smd circle
			(at -0.40005 0 270)
			(size 0 0)
			(layers "F.Cu" "F.Mask" "F.Paste")
			(net "SSD7_AUX_P3V3_EN_R")
		)
		(pad "2" smd circle
			(at 0.40005 0 270)
			(size 0 0)
			(layers "F.Cu" "F.Mask" "F.Paste")
			(net "P3V3_SSD7_CO_EN")
		)
	)
	(footprint ""
		(layer "F.Cu")
		(at 283.264356 -29.079952 180)
		(property "Reference" "R6207"
			(at 0 0 180)
			(layer "F.SilkS")
			(hide yes)
			(effects
				(font
					(size 1.27 1.27)
				)
			)
		)
		(property "Value" ""
			(at 0 0 180)
			(layer "F.Fab")
			(effects
				(font
					(size 1.27 1.27)
				)
			)
		)
		(duplicate_pad_numbers_are_jumpers no)
		(fp_line
			(start 0.7874 0.4064)
			(end -0.7874 0.4064)
			(stroke
				(width 0.1524)
				(type default)
			)
			(layer "F.SilkS")
		)
		(fp_line
			(start 0.7874 -0.4064)
			(end 0.7874 0.4064)
			(stroke
				(width 0.1524)
				(type default)
			)
			(layer "F.SilkS")
		)
		(fp_line
			(start -0.7874 0.4064)
			(end -0.7874 -0.4064)
			(stroke
				(width 0.1524)
				(type default)
			)
			(layer "F.SilkS")
		)
		(fp_line
			(start -0.7874 -0.4064)
			(end 0.7874 -0.4064)
			(stroke
				(width 0.1524)
				(type default)
			)
			(layer "F.SilkS")
		)
		(fp_line
			(start 0.67945 0.3048)
			(end 0.120396 0.3048)
			(stroke
				(width 0.1)
				(type default)
			)
			(layer "F.Fab")
		)
		(fp_line
			(start 0.67945 -0.3048)
			(end 0.67945 0.3048)
			(stroke
				(width 0.1)
				(type default)
			)
			(layer "F.Fab")
		)
		(fp_line
			(start 0.12065 -0.2794)
			(end 0.12065 -0.3048)
			(stroke
				(width 0.1)
				(type default)
			)
			(layer "F.Fab")
		)
		(fp_line
			(start 0.12065 -0.3048)
			(end 0.67945 -0.3048)
			(stroke
				(width 0.1)
				(type default)
			)
			(layer "F.Fab")
		)
		(fp_line
			(start 0.120396 0.3048)
			(end 0.120396 0.2794)
			(stroke
				(width 0.1)
				(type default)
			)
			(layer "F.Fab")
		)
		(fp_line
			(start 0.120396 0.2794)
			(end -0.12065 0.2794)
			(stroke
				(width 0.1)
				(type default)
			)
			(layer "F.Fab")
		)
		(fp_line
			(start -0.12065 0.3048)
			(end -0.67945 0.3048)
			(stroke
				(width 0.1)
				(type default)
			)
			(layer "F.Fab")
		)
		(fp_line
			(start -0.12065 0.2794)
			(end -0.12065 0.3048)
			(stroke
				(width 0.1)
				(type default)
			)
			(layer "F.Fab")
		)
		(fp_line
			(start -0.12065 -0.2794)
			(end 0.12065 -0.2794)
			(stroke
				(width 0.1)
				(type default)
			)
			(layer "F.Fab")
		)
		(fp_line
			(start -0.12065 -0.305054)
			(end -0.12065 -0.2794)
			(stroke
				(width 0.1)
				(type default)
			)
			(layer "F.Fab")
		)
		(fp_line
			(start -0.67945 0.3048)
			(end -0.67945 -0.305054)
			(stroke
				(width 0.1)
				(type default)
			)
			(layer "F.Fab")
		)
		(fp_line
			(start -0.67945 -0.305054)
			(end -0.12065 -0.305054)
			(stroke
				(width 0.1)
				(type default)
			)
			(layer "F.Fab")
		)
		(pad "1" smd circle
			(at -0.40005 0 180)
			(size 0 0)
			(layers "F.Cu" "F.Mask" "F.Paste")
			(net "GND")
		)
		(pad "2" smd circle
			(at 0.40005 0 180)
			(size 0 0)
			(layers "F.Cu" "F.Mask" "F.Paste")
			(net "SSD9_PWRDIS_R")
		)
	)
	(footprint ""
		(layer "F.Cu")
		(at 110.35538 -35.876738)
		(property "Reference" "R6056"
			(at 0 0 0)
			(layer "F.SilkS")
			(hide yes)
			(effects
				(font
					(size 1.27 1.27)
				)
			)
		)
		(property "Value" ""
			(at 0 0 0)
			(layer "F.Fab")
			(effects
				(font
					(size 1.27 1.27)
				)
			)
		)
		(duplicate_pad_numbers_are_jumpers no)
		(fp_line
			(start -0.7874 -0.4064)
			(end 0.7874 -0.4064)
			(stroke
				(width 0.1524)
				(type default)
			)
			(layer "F.SilkS")
		)
		(fp_line
			(start -0.7874 0.4064)
			(end -0.7874 -0.4064)
			(stroke
				(width 0.1524)
				(type default)
			)
			(layer "F.SilkS")
		)
		(fp_line
			(start 0.7874 -0.4064)
			(end 0.7874 0.4064)
			(stroke
				(width 0.1524)
				(type default)
			)
			(layer "F.SilkS")
		)
		(fp_line
			(start 0.7874 0.4064)
			(end -0.7874 0.4064)
			(stroke
				(width 0.1524)
				(type default)
			)
			(layer "F.SilkS")
		)
		(fp_line
			(start -0.67945 -0.305054)
			(end -0.12065 -0.305054)
			(stroke
				(width 0.1)
				(type default)
			)
			(layer "F.Fab")
		)
		(fp_line
			(start -0.67945 0.3048)
			(end -0.67945 -0.305054)
			(stroke
				(width 0.1)
				(type default)
			)
			(layer "F.Fab")
		)
		(fp_line
			(start -0.12065 -0.305054)
			(end -0.12065 -0.2794)
			(stroke
				(width 0.1)
				(type default)
			)
			(layer "F.Fab")
		)
		(fp_line
			(start -0.12065 -0.2794)
			(end 0.12065 -0.2794)
			(stroke
				(width 0.1)
				(type default)
			)
			(layer "F.Fab")
		)
		(fp_line
			(start -0.12065 0.2794)
			(end -0.12065 0.3048)
			(stroke
				(width 0.1)
				(type default)
			)
			(layer "F.Fab")
		)
		(fp_line
			(start -0.12065 0.3048)
			(end -0.67945 0.3048)
			(stroke
				(width 0.1)
				(type default)
			)
			(layer "F.Fab")
		)
		(fp_line
			(start 0.120396 0.2794)
			(end -0.12065 0.2794)
			(stroke
				(width 0.1)
				(type default)
			)
			(layer "F.Fab")
		)
		(fp_line
			(start 0.120396 0.3048)
			(end 0.120396 0.2794)
			(stroke
				(width 0.1)
				(type default)
			)
			(layer "F.Fab")
		)
		(fp_line
			(start 0.12065 -0.3048)
			(end 0.67945 -0.3048)
			(stroke
				(width 0.1)
				(type default)
			)
			(layer "F.Fab")
		)
		(fp_line
			(start 0.12065 -0.2794)
			(end 0.12065 -0.3048)
			(stroke
				(width 0.1)
				(type default)
			)
			(layer "F.Fab")
		)
		(fp_line
			(start 0.67945 -0.3048)
			(end 0.67945 0.3048)
			(stroke
				(width 0.1)
				(type default)
			)
			(layer "F.Fab")
		)
		(fp_line
			(start 0.67945 0.3048)
			(end 0.120396 0.3048)
			(stroke
				(width 0.1)
				(type default)
			)
			(layer "F.Fab")
		)
		(pad "1" smd circle
			(at -0.40005 0)
			(size 0 0)
			(layers "F.Cu" "F.Mask" "F.Paste")
			(net "P3V3_AUX")
		)
		(pad "2" smd circle
			(at 0.40005 0)
			(size 0 0)
			(layers "F.Cu" "F.Mask" "F.Paste")
			(net "PWRGD_P3V3_SSD4_D")
		)
	)
	(footprint ""
		(layer "F.Cu")
		(at 396.03426 -343.952322 90)
		(property "Reference" "C738"
			(at 0 0 90)
			(layer "F.SilkS")
			(hide yes)
			(effects
				(font
					(size 1.27 1.27)
				)
			)
		)
		(property "Value" ""
			(at 0 0 90)
			(layer "F.Fab")
			(effects
				(font
					(size 1.27 1.27)
				)
			)
		)
		(duplicate_pad_numbers_are_jumpers no)
		(fp_line
			(start 0.299974 -0.150114)
			(end 0.299974 0.150114)
			(stroke
				(width 0.1)
				(type default)
			)
			(layer "F.Fab")
		)
		(fp_line
			(start -0.299974 -0.150114)
			(end 0.299974 -0.150114)
			(stroke
				(width 0.1)
				(type default)
			)
			(layer "F.Fab")
		)
		(fp_line
			(start 0.299974 0.150114)
			(end -0.299974 0.150114)
			(stroke
				(width 0.1)
				(type default)
			)
			(layer "F.Fab")
		)
		(fp_line
			(start -0.299974 0.150114)
			(end -0.299974 -0.150114)
			(stroke
				(width 0.1)
				(type default)
			)
			(layer "F.Fab")
		)
		(pad "1" smd rect
			(at -0.2667 0 90)
			(size 0.3048 0.381)
			(layers "F.Cu" "F.Mask" "F.Paste")
			(net "P5E_PEX3_STN5_TX_DP<91>")
		)
		(pad "2" smd rect
			(at 0.2667 0 90)
			(size 0.3048 0.381)
			(layers "F.Cu" "F.Mask" "F.Paste")
			(net "P5E_PEX3_STN5_TX_C_DP<91>")
		)
	)
)
